FILE_TYPE = CONNECTIVITY;
{Allegro Design Entry HDL 17.2-2016 S081 (4005846) 1/11/2022}
"PAGE_NUMBER" = 114;
0"NC";
END.
